(kicad_pcb
	(version 20221018)
	(generator pcbnew)
	(general
    (thickness 1.518)
  )
	(paper "A4")
	(title_block
    (title "Kria K26 Devboard")
    (date "2024-03-26")
    (rev "1.2.5")
    (comment 1 "www.antmicro.com")
    (comment 2 "Antmicro Ltd.")
		(comment 9 "footprint 78 of 660 (J_SOM240_2), pads 101-199 of 242")
	)
	(layers
    (0 "F.Cu" mixed)
    (1 "In1.Cu" power)
    (2 "In2.Cu" mixed)
    (3 "In3.Cu" power)
    (4 "In4.Cu" mixed)
    (5 "In5.Cu" power)
    (6 "In6.Cu" mixed)
    (31 "B.Cu" power)
    (32 "B.Adhes" user "B.Adhesive")
    (33 "F.Adhes" user "F.Adhesive")
    (34 "B.Paste" user)
    (35 "F.Paste" user)
    (36 "B.SilkS" user "B.Silkscreen")
    (37 "F.SilkS" user "F.Silkscreen")
    (38 "B.Mask" user)
    (39 "F.Mask" user)
    (40 "Dwgs.User" user "User.Drawings")
    (41 "Cmts.User" user "User.Comments")
    (42 "Eco1.User" user "User.Eco1")
    (43 "Eco2.User" user "User.Eco2")
    (44 "Edge.Cuts" user)
    (45 "Margin" user)
    (46 "B.CrtYd" user "B.Courtyard")
    (47 "F.CrtYd" user "F.Courtyard")
    (48 "B.Fab" user)
    (49 "F.Fab" user)
  )
	(footprint "kria-k26-devboard-footprints:Conn_Plug_Samtec_ADM6_4x60_ADM6-60-01.5-L-4-2-A-TR"
    (layer "F.Cu")
    (at 158.177 117.6205 -90)
    (property "Author" "Antmicro")
    (property "DNP" "DNP")
    (property "License" "Apache-2.0")
    (property "MPN" "ADM6-60-01.5-L-4-2-A-TR")
    (property "Manufacturer" "Samtec")
    (property "Sheetfile" "k26_som.kicad_sch")
    (property "Sheetname" "Xilinx K26 SOM")
    (property "dnp" "")
    (property "exclude_from_bom" "")
    (property "ki_description" "Board to Board & Mezzanine Connectors 0.635 mm AcceleRate HD High-Density 4-Row Header 60P")
    (attr exclude_from_pos_files exclude_from_bom)
    (fp_text reference "J_SOM240_2" (at -14.0505 -3.623 90) (layer "F.SilkS")
        (effects (font (size 0.7 0.7) (thickness 0.15)) (justify right bottom))
    )
    (fp_text value "ADM6-60-01.5-L-4-2-A-TR" (at 0 3.7 90) (layer "F.Fab") hide
        (effects (font (size 0.7 0.7) (thickness 0.15)) (justify right bottom))
    )
    (pad "B39" smd circle (at -5.398 -0.791 270) (size 0.356 0.356) (layers "F.Cu" "F.Paste" "F.Mask")
      (net 541 "/Xilinx K26 SOM/HPC18_P") (pinfunction "B39") (pintype "passive"))
    (pad "B40" smd circle (at -6.033 -0.791 270) (size 0.356 0.356) (layers "F.Cu" "F.Paste" "F.Mask")
      (net 542 "/Xilinx K26 SOM/HPC18_N") (pinfunction "B40") (pintype "passive"))
    (pad "B41" smd circle (at -6.668 -0.791 270) (size 0.356 0.356) (layers "F.Cu" "F.Paste" "F.Mask")
      (net 1 "GND") (pinfunction "B41") (pintype "passive"))
    (pad "B42" smd circle (at -7.303 -0.791 270) (size 0.356 0.356) (layers "F.Cu" "F.Paste" "F.Mask")
      (net 543 "/Xilinx K26 SOM/VCCO_HPB_2") (pinfunction "B42") (pintype "passive"))
    (pad "B43" smd circle (at -7.938 -0.791 270) (size 0.356 0.356) (layers "F.Cu" "F.Paste" "F.Mask")
      (net 1 "GND") (pinfunction "B43") (pintype "passive"))
    (pad "B44" smd circle (at -8.573 -0.791 270) (size 0.356 0.356) (layers "F.Cu" "F.Paste" "F.Mask")
      (net 544 "/Xilinx K26 SOM/HDB12") (pinfunction "B44") (pintype "passive"))
    (pad "B45" smd circle (at -9.208 -0.791 270) (size 0.356 0.356) (layers "F.Cu" "F.Paste" "F.Mask")
      (net 545 "/Xilinx K26 SOM/HDB13") (pinfunction "B45") (pintype "passive"))
    (pad "B46" smd circle (at -9.843 -0.791 270) (size 0.356 0.356) (layers "F.Cu" "F.Paste" "F.Mask")
      (net 546 "/Xilinx K26 SOM/HDB14") (pinfunction "B46") (pintype "passive"))
    (pad "B47" smd circle (at -10.478 -0.791 270) (size 0.356 0.356) (layers "F.Cu" "F.Paste" "F.Mask")
      (net 1 "GND") (pinfunction "B47") (pintype "passive"))
    (pad "B48" smd circle (at -11.113 -0.791 270) (size 0.356 0.356) (layers "F.Cu" "F.Paste" "F.Mask")
      (net 547 "/Xilinx K26 SOM/HDB15") (pinfunction "B48") (pintype "passive"))
    (pad "B49" smd circle (at -11.748 -0.791 270) (size 0.356 0.356) (layers "F.Cu" "F.Paste" "F.Mask")
      (net 548 "/Xilinx K26 SOM/HDB16_CC") (pinfunction "B49") (pintype "passive"))
    (pad "B50" smd circle (at -12.383 -0.791 270) (size 0.356 0.356) (layers "F.Cu" "F.Paste" "F.Mask")
      (net 549 "/Xilinx K26 SOM/HDB17") (pinfunction "B50") (pintype "passive"))
    (pad "B51" smd circle (at -13.018 -0.791 270) (size 0.356 0.356) (layers "F.Cu" "F.Paste" "F.Mask")
      (net 1 "GND") (pinfunction "B51") (pintype "passive"))
    (pad "B52" smd circle (at -13.653 -0.791 270) (size 0.356 0.356) (layers "F.Cu" "F.Paste" "F.Mask")
      (net 550 "/Xilinx K26 SOM/HDC12") (pinfunction "B52") (pintype "passive"))
    (pad "B53" smd circle (at -14.288 -0.791 270) (size 0.356 0.356) (layers "F.Cu" "F.Paste" "F.Mask")
      (net 551 "/Xilinx K26 SOM/HDC13") (pinfunction "B53") (pintype "passive"))
    (pad "B54" smd circle (at -14.923 -0.791 270) (size 0.356 0.356) (layers "F.Cu" "F.Paste" "F.Mask")
      (net 552 "/Xilinx K26 SOM/HDC14") (pinfunction "B54") (pintype "passive"))
    (pad "B55" smd circle (at -15.558 -0.791 270) (size 0.356 0.356) (layers "F.Cu" "F.Paste" "F.Mask")
      (net 1 "GND") (pinfunction "B55") (pintype "passive"))
    (pad "B56" smd circle (at -16.193 -0.791 270) (size 0.356 0.356) (layers "F.Cu" "F.Paste" "F.Mask")
      (net 553 "/Xilinx K26 SOM/HDC15") (pinfunction "B56") (pintype "passive"))
    (pad "B57" smd circle (at -16.828 -0.791 270) (size 0.356 0.356) (layers "F.Cu" "F.Paste" "F.Mask")
      (net 554 "/Xilinx K26 SOM/HDC16_CC") (pinfunction "B57") (pintype "passive"))
    (pad "B58" smd circle (at -17.463 -0.791 270) (size 0.356 0.356) (layers "F.Cu" "F.Paste" "F.Mask")
      (net 555 "/Xilinx K26 SOM/HDC17") (pinfunction "B58") (pintype "passive"))
    (pad "B59" smd circle (at -18.098 -0.791 270) (size 0.356 0.356) (layers "F.Cu" "F.Paste" "F.Mask")
      (net 556 "/Xilinx K26 SOM/VCCO_HDB_1") (pinfunction "B59") (pintype "passive"))
    (pad "B60" smd circle (at -18.733 -0.791 270) (size 0.356 0.356) (layers "F.Cu" "F.Paste" "F.Mask")
      (net 557 "/Xilinx K26 SOM/VCCO_HDB_2") (pinfunction "B60") (pintype "passive"))
    (pad "C01" smd circle (at 18.732 0.79 270) (size 0.356 0.356) (layers "F.Cu" "F.Paste" "F.Mask")
      (net 1 "GND") (pinfunction "C01") (pintype "passive"))
    (pad "C02" smd circle (at 18.097 0.79 270) (size 0.356 0.356) (layers "F.Cu" "F.Paste" "F.Mask")
      (net 1 "GND") (pinfunction "C02") (pintype "passive"))
    (pad "C03" smd circle (at 17.462 0.79 270) (size 0.356 0.356) (layers "F.Cu" "F.Paste" "F.Mask")
      (net 558 "/Xilinx K26 SOM/GTH_REFCLK0_C2M_P") (pinfunction "C03") (pintype "passive"))
    (pad "C04" smd circle (at 16.827 0.79 270) (size 0.356 0.356) (layers "F.Cu" "F.Paste" "F.Mask")
      (net 559 "/Xilinx K26 SOM/GTH_REFCLK0_C2M_N") (pinfunction "C04") (pintype "passive"))
    (pad "C05" smd circle (at 16.192 0.79 270) (size 0.356 0.356) (layers "F.Cu" "F.Paste" "F.Mask")
      (net 1 "GND") (pinfunction "C05") (pintype "passive"))
    (pad "C06" smd circle (at 15.557 0.79 270) (size 0.356 0.356) (layers "F.Cu" "F.Paste" "F.Mask")
      (net 1 "GND") (pinfunction "C06") (pintype "passive"))
    (pad "C07" smd circle (at 14.922 0.79 270) (size 0.356 0.356) (layers "F.Cu" "F.Paste" "F.Mask")
      (net 560 "/Xilinx K26 SOM/GTH_DP1_M2C_P") (pinfunction "C07") (pintype "passive"))
    (pad "C08" smd circle (at 14.287 0.79 270) (size 0.356 0.356) (layers "F.Cu" "F.Paste" "F.Mask")
      (net 561 "/Xilinx K26 SOM/GTH_DP1_M2C_N") (pinfunction "C08") (pintype "passive"))
    (pad "C09" smd circle (at 13.652 0.79 270) (size 0.356 0.356) (layers "F.Cu" "F.Paste" "F.Mask")
      (net 1 "GND") (pinfunction "C09") (pintype "passive"))
    (pad "C10" smd circle (at 13.017 0.79 270) (size 0.356 0.356) (layers "F.Cu" "F.Paste" "F.Mask")
      (net 1 "GND") (pinfunction "C10") (pintype "passive"))
    (pad "C11" smd circle (at 12.382 0.79 270) (size 0.356 0.356) (layers "F.Cu" "F.Paste" "F.Mask")
      (net 562 "/Xilinx K26 SOM/HPB09_P") (pinfunction "C11") (pintype "passive"))
    (pad "C12" smd circle (at 11.747 0.79 270) (size 0.356 0.356) (layers "F.Cu" "F.Paste" "F.Mask")
      (net 563 "/Xilinx K26 SOM/HPB09_N") (pinfunction "C12") (pintype "passive"))
    (pad "C13" smd circle (at 11.112 0.79 270) (size 0.356 0.356) (layers "F.Cu" "F.Paste" "F.Mask")
      (net 1 "GND") (pinfunction "C13") (pintype "passive"))
    (pad "C14" smd circle (at 10.477 0.79 270) (size 0.356 0.356) (layers "F.Cu" "F.Paste" "F.Mask")
      (net 564 "/Xilinx K26 SOM/HPB14_P") (pinfunction "C14") (pintype "passive"))
    (pad "C15" smd circle (at 9.842 0.79 270) (size 0.356 0.356) (layers "F.Cu" "F.Paste" "F.Mask")
      (net 565 "/Xilinx K26 SOM/HPB14_N") (pinfunction "C15") (pintype "passive"))
    (pad "C16" smd circle (at 9.207 0.79 270) (size 0.356 0.356) (layers "F.Cu" "F.Paste" "F.Mask")
      (net 1 "GND") (pinfunction "C16") (pintype "passive"))
    (pad "C17" smd circle (at 8.572 0.79 270) (size 0.356 0.356) (layers "F.Cu" "F.Paste" "F.Mask")
      (net 566 "/Xilinx K26 SOM/HPB02_P") (pinfunction "C17") (pintype "passive"))
    (pad "C18" smd circle (at 7.937 0.79 270) (size 0.356 0.356) (layers "F.Cu" "F.Paste" "F.Mask")
      (net 567 "/Xilinx K26 SOM/HPB02_N") (pinfunction "C18") (pintype "passive"))
    (pad "C19" smd circle (at 7.302 0.79 270) (size 0.356 0.356) (layers "F.Cu" "F.Paste" "F.Mask")
      (net 1 "GND") (pinfunction "C19") (pintype "passive"))
    (pad "C20" smd circle (at 6.667 0.79 270) (size 0.356 0.356) (layers "F.Cu" "F.Paste" "F.Mask")
      (net 568 "/Xilinx K26 SOM/HPB13_P") (pinfunction "C20") (pintype "passive"))
    (pad "C21" smd circle (at 6.032 0.79 270) (size 0.356 0.356) (layers "F.Cu" "F.Paste" "F.Mask")
      (net 569 "/Xilinx K26 SOM/HPB13_N") (pinfunction "C21") (pintype "passive"))
    (pad "C22" smd circle (at 5.397 0.79 270) (size 0.356 0.356) (layers "F.Cu" "F.Paste" "F.Mask")
      (net 1 "GND") (pinfunction "C22") (pintype "passive"))
    (pad "C23" smd circle (at 4.762 0.79 270) (size 0.356 0.356) (layers "F.Cu" "F.Paste" "F.Mask")
      (net 570 "/Xilinx K26 SOM/HPB_18_P") (pinfunction "C23") (pintype "passive"))
    (pad "C24" smd circle (at 4.127 0.79 270) (size 0.356 0.356) (layers "F.Cu" "F.Paste" "F.Mask")
      (net 571 "/Xilinx K26 SOM/HPB_18_N") (pinfunction "C24") (pintype "passive"))
    (pad "C25" smd circle (at 3.492 0.79 270) (size 0.356 0.356) (layers "F.Cu" "F.Paste" "F.Mask")
      (net 1 "GND") (pinfunction "C25") (pintype "passive"))
    (pad "C26" smd circle (at 2.857 0.79 270) (size 0.356 0.356) (layers "F.Cu" "F.Paste" "F.Mask")
      (net 572 "/Xilinx K26 SOM/HPC17_P") (pinfunction "C26") (pintype "passive"))
    (pad "C27" smd circle (at 2.222 0.79 270) (size 0.356 0.356) (layers "F.Cu" "F.Paste" "F.Mask")
      (net 573 "/Xilinx K26 SOM/HPC17_N") (pinfunction "C27") (pintype "passive"))
    (pad "C28" smd circle (at 1.587 0.79 270) (size 0.356 0.356) (layers "F.Cu" "F.Paste" "F.Mask")
      (net 1 "GND") (pinfunction "C28") (pintype "passive"))
    (pad "C29" smd circle (at 0.952 0.79 270) (size 0.356 0.356) (layers "F.Cu" "F.Paste" "F.Mask")
      (net 574 "/Xilinx K26 SOM/HPC10_CC_P") (pinfunction "C29") (pintype "passive"))
    (pad "C30" smd circle (at 0.317 0.79 270) (size 0.356 0.356) (layers "F.Cu" "F.Paste" "F.Mask")
      (net 575 "/Xilinx K26 SOM/HPC10_CC_N") (pinfunction "C30") (pintype "passive"))
    (pad "C31" smd circle (at -0.318 0.79 270) (size 0.356 0.356) (layers "F.Cu" "F.Paste" "F.Mask")
      (net 1 "GND") (pinfunction "C31") (pintype "passive"))
    (pad "C32" smd circle (at -0.953 0.79 270) (size 0.356 0.356) (layers "F.Cu" "F.Paste" "F.Mask")
      (net 576 "/Xilinx K26 SOM/HPC11_P") (pinfunction "C32") (pintype "passive"))
    (pad "C33" smd circle (at -1.588 0.79 270) (size 0.356 0.356) (layers "F.Cu" "F.Paste" "F.Mask")
      (net 577 "/Xilinx K26 SOM/HPC11_N") (pinfunction "C33") (pintype "passive"))
    (pad "C34" smd circle (at -2.223 0.79 270) (size 0.356 0.356) (layers "F.Cu" "F.Paste" "F.Mask")
      (net 1 "GND") (pinfunction "C34") (pintype "passive"))
    (pad "C35" smd circle (at -2.858 0.79 270) (size 0.356 0.356) (layers "F.Cu" "F.Paste" "F.Mask")
      (net 578 "/Xilinx K26 SOM/HPC12_P") (pinfunction "C35") (pintype "passive"))
    (pad "C36" smd circle (at -3.493 0.79 270) (size 0.356 0.356) (layers "F.Cu" "F.Paste" "F.Mask")
      (net 579 "/Xilinx K26 SOM/HPC12_N") (pinfunction "C36") (pintype "passive"))
    (pad "C37" smd circle (at -4.128 0.79 270) (size 0.356 0.356) (layers "F.Cu" "F.Paste" "F.Mask")
      (net 1 "GND") (pinfunction "C37") (pintype "passive"))
    (pad "C38" smd circle (at -4.763 0.79 270) (size 0.356 0.356) (layers "F.Cu" "F.Paste" "F.Mask")
      (net 580 "/Xilinx K26 SOM/HPC05_CC_P") (pinfunction "C38") (pintype "passive"))
    (pad "C39" smd circle (at -5.398 0.79 270) (size 0.356 0.356) (layers "F.Cu" "F.Paste" "F.Mask")
      (net 581 "/Xilinx K26 SOM/HPC05_CC_N") (pinfunction "C39") (pintype "passive"))
    (pad "C40" smd circle (at -6.033 0.79 270) (size 0.356 0.356) (layers "F.Cu" "F.Paste" "F.Mask")
      (net 1 "GND") (pinfunction "C40") (pintype "passive"))
    (pad "C41" smd circle (at -6.668 0.79 270) (size 0.356 0.356) (layers "F.Cu" "F.Paste" "F.Mask")
      (net 582 "/Xilinx K26 SOM/HPC_CLK0_P") (pinfunction "C41") (pintype "passive"))
    (pad "C42" smd circle (at -7.303 0.79 270) (size 0.356 0.356) (layers "F.Cu" "F.Paste" "F.Mask")
      (net 583 "/Xilinx K26 SOM/HPC_CLK0_N") (pinfunction "C42") (pintype "passive"))
    (pad "C43" smd circle (at -7.938 0.79 270) (size 0.356 0.356) (layers "F.Cu" "F.Paste" "F.Mask")
      (net 1 "GND") (pinfunction "C43") (pintype "passive"))
    (pad "C44" smd circle (at -8.573 0.79 270) (size 0.356 0.356) (layers "F.Cu" "F.Paste" "F.Mask")
      (net 584 "/Xilinx K26 SOM/VCCO_HPC_1") (pinfunction "C44") (pintype "passive"))
    (pad "C45" smd circle (at -9.208 0.79 270) (size 0.356 0.356) (layers "F.Cu" "F.Paste" "F.Mask")
      (net 1 "GND") (pinfunction "C45") (pintype "passive"))
    (pad "C46" smd circle (at -9.843 0.79 270) (size 0.356 0.356) (layers "F.Cu" "F.Paste" "F.Mask")
      (net 585 "/Xilinx K26 SOM/HDB06") (pinfunction "C46") (pintype "passive"))
    (pad "C47" smd circle (at -10.478 0.79 270) (size 0.356 0.356) (layers "F.Cu" "F.Paste" "F.Mask")
      (net 586 "/Xilinx K26 SOM/HDB07") (pinfunction "C47") (pintype "passive"))
    (pad "C48" smd circle (at -11.113 0.79 270) (size 0.356 0.356) (layers "F.Cu" "F.Paste" "F.Mask")
      (net 587 "/Xilinx K26 SOM/HDB08_CC") (pinfunction "C48") (pintype "passive"))
    (pad "C49" smd circle (at -11.748 0.79 270) (size 0.356 0.356) (layers "F.Cu" "F.Paste" "F.Mask")
      (net 1 "GND") (pinfunction "C49") (pintype "passive"))
    (pad "C50" smd circle (at -12.383 0.79 270) (size 0.356 0.356) (layers "F.Cu" "F.Paste" "F.Mask")
      (net 588 "/Xilinx K26 SOM/HDB09") (pinfunction "C50") (pintype "passive"))
    (pad "C51" smd circle (at -13.018 0.79 270) (size 0.356 0.356) (layers "F.Cu" "F.Paste" "F.Mask")
      (net 589 "/Xilinx K26 SOM/HDB10") (pinfunction "C51") (pintype "passive"))
    (pad "C52" smd circle (at -13.653 0.79 270) (size 0.356 0.356) (layers "F.Cu" "F.Paste" "F.Mask")
      (net 590 "/Xilinx K26 SOM/HDB11") (pinfunction "C52") (pintype "passive"))
    (pad "C53" smd circle (at -14.288 0.79 270) (size 0.356 0.356) (layers "F.Cu" "F.Paste" "F.Mask")
      (net 1 "GND") (pinfunction "C53") (pintype "passive"))
    (pad "C54" smd circle (at -14.923 0.79 270) (size 0.356 0.356) (layers "F.Cu" "F.Paste" "F.Mask")
      (net 591 "/Xilinx K26 SOM/HDC06") (pinfunction "C54") (pintype "passive"))
    (pad "C55" smd circle (at -15.558 0.79 270) (size 0.356 0.356) (layers "F.Cu" "F.Paste" "F.Mask")
      (net 592 "/Xilinx K26 SOM/HDC07") (pinfunction "C55") (pintype "passive"))
    (pad "C56" smd circle (at -16.193 0.79 270) (size 0.356 0.356) (layers "F.Cu" "F.Paste" "F.Mask")
      (net 593 "/Xilinx K26 SOM/HDC08_CC") (pinfunction "C56") (pintype "passive"))
    (pad "C57" smd circle (at -16.828 0.79 270) (size 0.356 0.356) (layers "F.Cu" "F.Paste" "F.Mask")
      (net 1 "GND") (pinfunction "C57") (pintype "passive"))
    (pad "C58" smd circle (at -17.463 0.79 270) (size 0.356 0.356) (layers "F.Cu" "F.Paste" "F.Mask")
      (net 594 "/Xilinx K26 SOM/HDC09") (pinfunction "C58") (pintype "passive"))
    (pad "C59" smd circle (at -18.098 0.79 270) (size 0.356 0.356) (layers "F.Cu" "F.Paste" "F.Mask")
      (net 595 "/Xilinx K26 SOM/HDC10") (pinfunction "C59") (pintype "passive"))
    (pad "C60" smd circle (at -18.733 0.79 270) (size 0.356 0.356) (layers "F.Cu" "F.Paste" "F.Mask")
      (net 596 "/Xilinx K26 SOM/HDC11") (pinfunction "C60") (pintype "passive"))
    (pad "D01" smd circle (at 18.732 1.749 270) (size 0.356 0.356) (layers "F.Cu" "F.Paste" "F.Mask")
      (net 597 "/Xilinx K26 SOM/GTH_DP1_C2M_P") (pinfunction "D01") (pintype "passive"))
    (pad "D02" smd circle (at 18.097 1.749 270) (size 0.356 0.356) (layers "F.Cu" "F.Paste" "F.Mask")
      (net 598 "/Xilinx K26 SOM/GTH_DP1_C2M_N") (pinfunction "D02") (pintype "passive"))
    (pad "D03" smd circle (at 17.462 1.749 270) (size 0.356 0.356) (layers "F.Cu" "F.Paste" "F.Mask")
      (net 1 "GND") (pinfunction "D03") (pintype "passive"))
    (pad "D04" smd circle (at 16.827 1.749 270) (size 0.356 0.356) (layers "F.Cu" "F.Paste" "F.Mask")
      (net 1 "GND") (pinfunction "D04") (pintype "passive"))
    (pad "D05" smd circle (at 16.192 1.749 270) (size 0.356 0.356) (layers "F.Cu" "F.Paste" "F.Mask")
      (net 599 "/Xilinx K26 SOM/GTH_DP3_C2M_P") (pinfunction "D05") (pintype "passive"))
    (pad "D06" smd circle (at 15.557 1.749 270) (size 0.356 0.356) (layers "F.Cu" "F.Paste" "F.Mask")
      (net 600 "/Xilinx K26 SOM/GTH_DP3_C2M_N") (pinfunction "D06") (pintype "passive"))
    (pad "D07" smd circle (at 14.922 1.749 270) (size 0.356 0.356) (layers "F.Cu" "F.Paste" "F.Mask")
      (net 1 "GND") (pinfunction "D07") (pintype "passive"))
    (pad "D08" smd circle (at 14.287 1.749 270) (size 0.356 0.356) (layers "F.Cu" "F.Paste" "F.Mask")
      (net 1 "GND") (pinfunction "D08") (pintype "passive"))
    (pad "D09" smd circle (at 13.652 1.749 270) (size 0.356 0.356) (layers "F.Cu" "F.Paste" "F.Mask")
      (net 601 "/Xilinx K26 SOM/GTH_DP0_M2C_P") (pinfunction "D09") (pintype "passive"))
    (pad "D10" smd circle (at 13.017 1.749 270) (size 0.356 0.356) (layers "F.Cu" "F.Paste" "F.Mask")
      (net 602 "/Xilinx K26 SOM/GTH_DP0_M2C_N") (pinfunction "D10") (pintype "passive"))
    (pad "D11" smd circle (at 12.382 1.749 270) (size 0.356 0.356) (layers "F.Cu" "F.Paste" "F.Mask")
      (net 1 "GND") (pinfunction "D11") (pintype "passive"))
    (pad "D12" smd circle (at 11.747 1.749 270) (size 0.356 0.356) (layers "F.Cu" "F.Paste" "F.Mask")
      (net 603 "/Xilinx K26 SOM/HPB01_P") (pinfunction "D12") (pintype "passive"))
    (pad "D13" smd circle (at 11.112 1.749 270) (size 0.356 0.356) (layers "F.Cu" "F.Paste" "F.Mask")
      (net 604 "/Xilinx K26 SOM/HPB01_N") (pinfunction "D13") (pintype "passive"))
    (pad "D14" smd circle (at 10.477 1.749 270) (size 0.356 0.356) (layers "F.Cu" "F.Paste" "F.Mask")
      (net 1 "GND") (pinfunction "D14") (pintype "passive"))
    (pad "D15" smd circle (at 9.842 1.749 270) (size 0.356 0.356) (layers "F.Cu" "F.Paste" "F.Mask")
      (net 605 "/Xilinx K26 SOM/HPB00_CC_P") (pinfunction "D15") (pintype "passive"))
    (pad "D16" smd circle (at 9.207 1.749 270) (size 0.356 0.356) (layers "F.Cu" "F.Paste" "F.Mask")
      (net 606 "/Xilinx K26 SOM/HPB00_CC_N") (pinfunction "D16") (pintype "passive"))
    (pad "D17" smd circle (at 8.572 1.749 270) (size 0.356 0.356) (layers "F.Cu" "F.Paste" "F.Mask")
      (net 1 "GND") (pinfunction "D17") (pintype "passive"))
  )
)
